(kicad_pcb
	(version 20241229)
	(generator "pcbnew")
	(generator_version "9.0")
	(general
		(thickness 1.292)
		(legacy_teardrops no)
	)
	(paper "A4")
	(title_block
		(title "LPDDR5 Testbed")
		(date "2023-12-19")
		(rev "1.0.0")
		(comment 9 "footprints 102-107 of 160")
	)
	(layers
		(0 "F.Cu" signal)
		(4 "In1.Cu" power)
		(6 "In2.Cu" power)
		(8 "In3.Cu" signal)
		(10 "In4.Cu" signal)
		(2 "B.Cu" signal)
		(9 "F.Adhes" user "F.Adhesive")
		(11 "B.Adhes" user "B.Adhesive")
		(13 "F.Paste" user)
		(15 "B.Paste" user)
		(5 "F.SilkS" user "F.Silkscreen")
		(7 "B.SilkS" user "B.Silkscreen")
		(1 "F.Mask" user)
		(3 "B.Mask" user)
		(17 "Dwgs.User" user "User.Drawings")
		(19 "Cmts.User" user "User.Comments")
		(21 "Eco1.User" user "User.Eco1")
		(23 "Eco2.User" user "User.Eco2")
		(25 "Edge.Cuts" user)
		(27 "Margin" user)
		(31 "F.CrtYd" user "F.Courtyard")
		(29 "B.CrtYd" user "B.Courtyard")
		(35 "F.Fab" user)
		(33 "B.Fab" user)
	)
	(footprint "antmicro-footprints:R_Array_4x0402_Panasonic_EXB28V"
		(layer "B.Cu")
		(at 108.85 93.8)
		(property "Reference" "R24"
			(at 0.95 1.8 0)
			(unlocked yes)
			(layer "B.SilkS")
			(effects
				(font
					(size 0.7 0.7)
					(thickness 0.15)
				)
				(justify left bottom mirror)
			)
		)
		(property "Value" "R_4x100R_0402_array"
			(at -1.5 -2 180)
			(layer "B.Fab")
			(effects
				(font
					(size 0.7 0.7)
					(thickness 0.15)
				)
				(justify left bottom mirror)
			)
		)
		(property "Author" "Antmicro"
			(at 0 0 0)
			(layer "B.Fab")
			(hide yes)
			(effects
				(font
					(size 1 1)
					(thickness 0.15)
				)
				(justify mirror)
			)
		)
		(property "License" "Apache-2.0"
			(at 0 0 0)
			(layer "B.Fab")
			(hide yes)
			(effects
				(font
					(size 1 1)
					(thickness 0.15)
				)
				(justify mirror)
			)
		)
		(property "MPN" "EXB-28V101JX"
			(at 0 0 0)
			(layer "B.Fab")
			(hide yes)
			(effects
				(font
					(size 1 1)
					(thickness 0.15)
				)
				(justify mirror)
			)
		)
		(property "Manufacturer" "Panasonic"
			(at 0 0 0)
			(layer "B.Fab")
			(hide yes)
			(effects
				(font
					(size 1 1)
					(thickness 0.15)
				)
				(justify mirror)
			)
		)
		(property "Val" "R_4x100R_0402"
			(at 0 0 0)
			(layer "B.Fab")
			(hide yes)
			(effects
				(font
					(size 1 1)
					(thickness 0.15)
				)
				(justify mirror)
			)
		)
		(sheetname "Translators")
		(sheetfile "translators.kicad_sch")
		(attr smd)
		(fp_line
			(start -1.25 0.5)
			(end -1.25 -0.498)
			(stroke
				(width 0.15)
				(type solid)
			)
			(layer "B.SilkS")
		)
		(fp_line
			(start 1.25 -0.499)
			(end 1.25 0.499)
			(stroke
				(width 0.15)
				(type solid)
			)
			(layer "B.SilkS")
		)
		(fp_rect
			(start -1.25 0.8)
			(end 1.25 -0.8)
			(stroke
				(width 0.05)
				(type solid)
			)
			(fill no)
			(layer "B.CrtYd")
		)
		(fp_line
			(start -1 -0.498)
			(end -1 0.5)
			(stroke
				(width 0.15)
				(type solid)
			)
			(layer "B.Fab")
		)
		(fp_line
			(start -1 0.5)
			(end 0.998 0.5)
			(stroke
				(width 0.15)
				(type solid)
			)
			(layer "B.Fab")
		)
		(fp_line
			(start 0.998 -0.498)
			(end -1 -0.498)
			(stroke
				(width 0.15)
				(type solid)
			)
			(layer "B.Fab")
		)
		(fp_line
			(start 0.998 0.5)
			(end 0.998 -0.498)
			(stroke
				(width 0.15)
				(type solid)
			)
			(layer "B.Fab")
		)
		(pad "1" smd roundrect
			(at -0.8875 -0.45)
			(size 0.525 0.5)
			(layers "B.Cu" "B.Mask" "B.Paste")
			(roundrect_rratio 0.25)
			(net 191 "/LPDDR5/LPDDR5_A.DQ15")
			(pinfunction "R1.1")
			(pintype "passive")
		)
		(pad "2" smd roundrect
			(at -0.25 -0.45)
			(size 0.25 0.5)
			(layers "B.Cu" "B.Mask" "B.Paste")
			(roundrect_rratio 0.25)
			(net 192 "/LPDDR5/LPDDR5_A.DQ14")
			(pinfunction "R2.1")
			(pintype "passive")
		)
		(pad "3" smd roundrect
			(at 0.25 -0.45)
			(size 0.25 0.5)
			(layers "B.Cu" "B.Mask" "B.Paste")
			(roundrect_rratio 0.25)
			(net 193 "/LPDDR5/LPDDR5_A.DQ12")
			(pinfunction "R3.1")
			(pintype "passive")
		)
		(pad "4" smd roundrect
			(at 0.8875 -0.45)
			(size 0.525 0.5)
			(layers "B.Cu" "B.Mask" "B.Paste")
			(roundrect_rratio 0.25)
			(net 194 "/LPDDR5/LPDDR5_A.DQ13")
			(pinfunction "R4.1")
			(pintype "passive")
		)
		(pad "5" smd roundrect
			(at 0.8875 0.45)
			(size 0.525 0.5)
			(layers "B.Cu" "B.Mask" "B.Paste")
			(roundrect_rratio 0.25)
			(net 14 "GND")
			(pinfunction "R4.2")
			(pintype "passive")
		)
		(pad "6" smd roundrect
			(at 0.25 0.45)
			(size 0.25 0.5)
			(layers "B.Cu" "B.Mask" "B.Paste")
			(roundrect_rratio 0.25)
			(net 14 "GND")
			(pinfunction "R3.2")
			(pintype "passive")
		)
		(pad "7" smd roundrect
			(at -0.25 0.45)
			(size 0.25 0.5)
			(layers "B.Cu" "B.Mask" "B.Paste")
			(roundrect_rratio 0.25)
			(net 14 "GND")
			(pinfunction "R2.2")
			(pintype "passive")
		)
		(pad "8" smd roundrect
			(at -0.8875 0.45)
			(size 0.525 0.5)
			(layers "B.Cu" "B.Mask" "B.Paste")
			(roundrect_rratio 0.25)
			(net 14 "GND")
			(pinfunction "R1.2")
			(pintype "passive")
		)
	)
	(footprint "antmicro-footprints:R_0402_1005Metric"
		(layer "B.Cu")
		(at 118.13 90.94 90)
		(descr "Resistor SMD 0402")
		(tags "resistor SMD 0402")
		(property "Reference" "R12"
			(at -1.36 1.37 90)
			(unlocked yes)
			(layer "B.SilkS")
			(effects
				(font
					(size 0.7 0.7)
					(thickness 0.15)
				)
				(justify right bottom mirror)
			)
		)
		(property "Value" "R_100R_0402"
			(at -1.011843 -1.772047 90)
			(layer "B.Fab")
			(effects
				(font
					(size 0.7 0.7)
					(thickness 0.15)
				)
				(justify right bottom mirror)
			)
		)
		(property "Author" "Antmicro"
			(at 209.07 -27.19 0)
			(layer "B.Fab")
			(hide yes)
			(effects
				(font
					(size 1 1)
					(thickness 0.15)
				)
				(justify mirror)
			)
		)
		(property "License" "Apache-2.0"
			(at 209.07 -27.19 0)
			(layer "B.Fab")
			(hide yes)
			(effects
				(font
					(size 1 1)
					(thickness 0.15)
				)
				(justify mirror)
			)
		)
		(property "MPN" "CR0402-FX-1000GLF"
			(at 209.07 -27.19 0)
			(layer "B.Fab")
			(hide yes)
			(effects
				(font
					(size 1 1)
					(thickness 0.15)
				)
				(justify mirror)
			)
		)
		(property "Manufacturer" "Bourns"
			(at 209.07 -27.19 0)
			(layer "B.Fab")
			(hide yes)
			(effects
				(font
					(size 1 1)
					(thickness 0.15)
				)
				(justify mirror)
			)
		)
		(property "Tolerance" "1%"
			(at 209.07 -27.19 0)
			(layer "B.Fab")
			(hide yes)
			(effects
				(font
					(size 1 1)
					(thickness 0.15)
				)
				(justify mirror)
			)
		)
		(property "Val" "100R"
			(at 209.07 -27.19 0)
			(layer "B.Fab")
			(hide yes)
			(effects
				(font
					(size 1 1)
					(thickness 0.15)
				)
				(justify mirror)
			)
		)
		(sheetname "Translators")
		(sheetfile "translators.kicad_sch")
		(attr smd)
		(fp_rect
			(start -0.93 0.47)
			(end 0.93 -0.47)
			(stroke
				(width 0.05)
				(type solid)
			)
			(fill no)
			(layer "B.CrtYd")
		)
		(fp_rect
			(start -0.5 0.25)
			(end 0.5 -0.25)
			(stroke
				(width 0.15)
				(type solid)
			)
			(fill no)
			(layer "B.Fab")
		)
		(pad "1" smd roundrect
			(at -0.485 0 90)
			(size 0.59 0.64)
			(layers "B.Cu" "B.Mask" "B.Paste")
			(roundrect_rratio 0.25)
			(net 170 "/SODIMM/LPDDR5_IN_A.WCK0_P")
			(pintype "passive")
		)
		(pad "2" smd roundrect
			(at 0.485 0 90)
			(size 0.59 0.64)
			(layers "B.Cu" "B.Mask" "B.Paste")
			(roundrect_rratio 0.25)
			(net 45 "/LPDDR5/LPDDR5_A.WCK0_P")
			(pintype "passive")
		)
	)
	(footprint "antmicro-footprints:C_0402_1005Metric"
		(layer "B.Cu")
		(at 104.875 70.641 -90)
		(descr "Capacitor SMD 0402")
		(tags "capacitor SMD 0402")
		(property "Reference" "C12"
			(at -1.141 0.675 90)
			(unlocked yes)
			(layer "B.SilkS")
			(effects
				(font
					(size 0.7 0.7)
					(thickness 0.15)
				)
				(justify left bottom mirror)
			)
		)
		(property "Value" "C_1u_0402"
			(at -1.022927 -2.155213 90)
			(layer "B.Fab")
			(effects
				(font
					(size 0.7 0.7)
					(thickness 0.15)
				)
				(justify left bottom mirror)
			)
		)
		(property "Author" "Antmicro"
			(at 34.234 175.516 0)
			(layer "B.Fab")
			(hide yes)
			(effects
				(font
					(size 1 1)
					(thickness 0.15)
				)
				(justify mirror)
			)
		)
		(property "Dielectric" ""
			(at 34.234 175.516 0)
			(layer "B.Fab")
			(hide yes)
			(effects
				(font
					(size 1 1)
					(thickness 0.15)
				)
				(justify mirror)
			)
		)
		(property "License" "Apache-2.0"
			(at 34.234 175.516 0)
			(layer "B.Fab")
			(hide yes)
			(effects
				(font
					(size 1 1)
					(thickness 0.15)
				)
				(justify mirror)
			)
		)
		(property "MPN" "C1005X6S1A105K050BC"
			(at 34.234 175.516 0)
			(layer "B.Fab")
			(hide yes)
			(effects
				(font
					(size 1 1)
					(thickness 0.15)
				)
				(justify mirror)
			)
		)
		(property "Manufacturer" "TDK"
			(at 34.234 175.516 0)
			(layer "B.Fab")
			(hide yes)
			(effects
				(font
					(size 1 1)
					(thickness 0.15)
				)
				(justify mirror)
			)
		)
		(property "Val" "1u"
			(at 34.234 175.516 0)
			(layer "B.Fab")
			(hide yes)
			(effects
				(font
					(size 1 1)
					(thickness 0.15)
				)
				(justify mirror)
			)
		)
		(property "Voltage" ""
			(at 34.234 175.516 0)
			(layer "B.Fab")
			(hide yes)
			(effects
				(font
					(size 1 1)
					(thickness 0.15)
				)
				(justify mirror)
			)
		)
		(sheetname "Power supply")
		(sheetfile "power_supply.kicad_sch")
		(attr smd)
		(fp_rect
			(start -0.9659 0.481258)
			(end 0.9649 -0.458742)
			(stroke
				(width 0.05)
				(type solid)
			)
			(fill no)
			(layer "B.CrtYd")
		)
		(fp_line
			(start -0.499 0.25)
			(end 0.499 0.25)
			(stroke
				(width 0.15)
				(type solid)
			)
			(layer "B.Fab")
		)
		(fp_line
			(start 0.499 0.25)
			(end 0.499 -0.248)
			(stroke
				(width 0.15)
				(type solid)
			)
			(layer "B.Fab")
		)
		(fp_line
			(start -0.499 -0.248)
			(end -0.499 0.25)
			(stroke
				(width 0.15)
				(type solid)
			)
			(layer "B.Fab")
		)
		(fp_line
			(start 0.499 -0.248)
			(end -0.499 -0.248)
			(stroke
				(width 0.15)
				(type solid)
			)
			(layer "B.Fab")
		)
		(pad "1" smd roundrect
			(at -0.484 0 270)
			(size 0.59 0.64)
			(layers "B.Cu" "B.Mask" "B.Paste")
			(roundrect_rratio 0.25)
			(net 14 "GND")
			(pintype "passive")
		)
		(pad "2" smd roundrect
			(at 0.484 0 270)
			(size 0.59 0.64)
			(layers "B.Cu" "B.Mask" "B.Paste")
			(roundrect_rratio 0.25)
			(net 117 "Net-(C12-Pad2)")
			(pintype "passive")
		)
	)
	(footprint "antmicro-footprints:R_0402_1005Metric"
		(layer "B.Cu")
		(at 155.9 92)
		(descr "Resistor SMD 0402")
		(tags "resistor SMD 0402")
		(property "Reference" "R91"
			(at 1 -0.2 0)
			(unlocked yes)
			(layer "B.SilkS")
			(effects
				(font
					(size 0.7 0.7)
					(thickness 0.15)
				)
				(justify right bottom mirror)
			)
		)
		(property "Value" "R_100R_0402"
			(at -1.011843 -1.772047 0)
			(layer "B.Fab")
			(effects
				(font
					(size 0.7 0.7)
					(thickness 0.15)
				)
				(justify right bottom mirror)
			)
		)
		(property "Author" "Antmicro"
			(at 0 0 0)
			(layer "B.Fab")
			(hide yes)
			(effects
				(font
					(size 1 1)
					(thickness 0.15)
				)
				(justify mirror)
			)
		)
		(property "License" "Apache-2.0"
			(at 0 0 0)
			(layer "B.Fab")
			(hide yes)
			(effects
				(font
					(size 1 1)
					(thickness 0.15)
				)
				(justify mirror)
			)
		)
		(property "MPN" "CR0402-FX-1000GLF"
			(at 0 0 0)
			(layer "B.Fab")
			(hide yes)
			(effects
				(font
					(size 1 1)
					(thickness 0.15)
				)
				(justify mirror)
			)
		)
		(property "Manufacturer" "Bourns"
			(at 0 0 0)
			(layer "B.Fab")
			(hide yes)
			(effects
				(font
					(size 1 1)
					(thickness 0.15)
				)
				(justify mirror)
			)
		)
		(property "Tolerance" "1%"
			(at 0 0 0)
			(layer "B.Fab")
			(hide yes)
			(effects
				(font
					(size 1 1)
					(thickness 0.15)
				)
				(justify mirror)
			)
		)
		(property "Val" "100R"
			(at 0 0 0)
			(layer "B.Fab")
			(hide yes)
			(effects
				(font
					(size 1 1)
					(thickness 0.15)
				)
				(justify mirror)
			)
		)
		(sheetname "Translators1")
		(sheetfile "translators.kicad_sch")
		(attr smd)
		(fp_rect
			(start -0.93 0.47)
			(end 0.93 -0.47)
			(stroke
				(width 0.05)
				(type solid)
			)
			(fill no)
			(layer "B.CrtYd")
		)
		(fp_rect
			(start -0.5 0.25)
			(end 0.5 -0.25)
			(stroke
				(width 0.15)
				(type solid)
			)
			(fill no)
			(layer "B.Fab")
		)
		(pad "1" smd roundrect
			(at -0.485 0)
			(size 0.59 0.64)
			(layers "B.Cu" "B.Mask" "B.Paste")
			(roundrect_rratio 0.25)
			(net 223 "/LPDDR5/LPDDR5_B.DMI1")
			(pintype "passive")
		)
		(pad "2" smd roundrect
			(at 0.485 0)
			(size 0.59 0.64)
			(layers "B.Cu" "B.Mask" "B.Paste")
			(roundrect_rratio 0.25)
			(net 14 "GND")
			(pintype "passive")
		)
	)
	(footprint "antmicro-footprints:R_Array_4x0402_Panasonic_EXB28V"
		(layer "B.Cu")
		(at 166.2 93.8)
		(property "Reference" "R72"
			(at -1.1 1.8 0)
			(unlocked yes)
			(layer "B.SilkS")
			(effects
				(font
					(size 0.7 0.7)
					(thickness 0.15)
				)
				(justify right bottom mirror)
			)
		)
		(property "Value" "R_4x100R_0402_array"
			(at -1.5 -2 0)
			(layer "B.Fab")
			(effects
				(font
					(size 0.7 0.7)
					(thickness 0.15)
				)
				(justify right bottom mirror)
			)
		)
		(property "Author" "Antmicro"
			(at 0 0 0)
			(layer "B.Fab")
			(hide yes)
			(effects
				(font
					(size 1 1)
					(thickness 0.15)
				)
				(justify mirror)
			)
		)
		(property "License" "Apache-2.0"
			(at 0 0 0)
			(layer "B.Fab")
			(hide yes)
			(effects
				(font
					(size 1 1)
					(thickness 0.15)
				)
				(justify mirror)
			)
		)
		(property "MPN" "EXB-28V101JX"
			(at 0 0 0)
			(layer "B.Fab")
			(hide yes)
			(effects
				(font
					(size 1 1)
					(thickness 0.15)
				)
				(justify mirror)
			)
		)
		(property "Manufacturer" "Panasonic"
			(at 0 0 0)
			(layer "B.Fab")
			(hide yes)
			(effects
				(font
					(size 1 1)
					(thickness 0.15)
				)
				(justify mirror)
			)
		)
		(property "Val" "R_4x100R_0402"
			(at 0 0 0)
			(layer "B.Fab")
			(hide yes)
			(effects
				(font
					(size 1 1)
					(thickness 0.15)
				)
				(justify mirror)
			)
		)
		(sheetname "Translators1")
		(sheetfile "translators.kicad_sch")
		(attr smd)
		(fp_line
			(start -1.25 0.5)
			(end -1.25 -0.498)
			(stroke
				(width 0.15)
				(type solid)
			)
			(layer "B.SilkS")
		)
		(fp_line
			(start 1.25 -0.499)
			(end 1.25 0.499)
			(stroke
				(width 0.15)
				(type solid)
			)
			(layer "B.SilkS")
		)
		(fp_rect
			(start -1.25 0.8)
			(end 1.25 -0.8)
			(stroke
				(width 0.05)
				(type solid)
			)
			(fill no)
			(layer "B.CrtYd")
		)
		(fp_line
			(start -1 -0.498)
			(end -1 0.5)
			(stroke
				(width 0.15)
				(type solid)
			)
			(layer "B.Fab")
		)
		(fp_line
			(start -1 0.5)
			(end 0.998 0.5)
			(stroke
				(width 0.15)
				(type solid)
			)
			(layer "B.Fab")
		)
		(fp_line
			(start 0.998 -0.498)
			(end -1 -0.498)
			(stroke
				(width 0.15)
				(type solid)
			)
			(layer "B.Fab")
		)
		(fp_line
			(start 0.998 0.5)
			(end 0.998 -0.498)
			(stroke
				(width 0.15)
				(type solid)
			)
			(layer "B.Fab")
		)
		(pad "1" smd roundrect
			(at -0.8875 -0.45)
			(size 0.525 0.5)
			(layers "B.Cu" "B.Mask" "B.Paste")
			(roundrect_rratio 0.25)
			(net 224 "/LPDDR5/LPDDR5_B.DQ3")
			(pinfunction "R1.1")
			(pintype "passive")
		)
		(pad "2" smd roundrect
			(at -0.25 -0.45)
			(size 0.25 0.5)
			(layers "B.Cu" "B.Mask" "B.Paste")
			(roundrect_rratio 0.25)
			(net 226 "/LPDDR5/LPDDR5_B.DQ1")
			(pinfunction "R2.1")
			(pintype "passive")
		)
		(pad "3" smd roundrect
			(at 0.25 -0.45)
			(size 0.25 0.5)
			(layers "B.Cu" "B.Mask" "B.Paste")
			(roundrect_rratio 0.25)
			(net 225 "/LPDDR5/LPDDR5_B.DQ2")
			(pinfunction "R3.1")
			(pintype "passive")
		)
		(pad "4" smd roundrect
			(at 0.8875 -0.45)
			(size 0.525 0.5)
			(layers "B.Cu" "B.Mask" "B.Paste")
			(roundrect_rratio 0.25)
			(net 227 "/LPDDR5/LPDDR5_B.DQ0")
			(pinfunction "R4.1")
			(pintype "passive")
		)
		(pad "5" smd roundrect
			(at 0.8875 0.45)
			(size 0.525 0.5)
			(layers "B.Cu" "B.Mask" "B.Paste")
			(roundrect_rratio 0.25)
			(net 14 "GND")
			(pinfunction "R4.2")
			(pintype "passive")
		)
		(pad "6" smd roundrect
			(at 0.25 0.45)
			(size 0.25 0.5)
			(layers "B.Cu" "B.Mask" "B.Paste")
			(roundrect_rratio 0.25)
			(net 14 "GND")
			(pinfunction "R3.2")
			(pintype "passive")
		)
		(pad "7" smd roundrect
			(at -0.25 0.45)
			(size 0.25 0.5)
			(layers "B.Cu" "B.Mask" "B.Paste")
			(roundrect_rratio 0.25)
			(net 14 "GND")
			(pinfunction "R2.2")
			(pintype "passive")
		)
		(pad "8" smd roundrect
			(at -0.8875 0.45)
			(size 0.525 0.5)
			(layers "B.Cu" "B.Mask" "B.Paste")
			(roundrect_rratio 0.25)
			(net 14 "GND")
			(pinfunction "R1.2")
			(pintype "passive")
		)
	)
	(footprint "antmicro-footprints:C_0402_1005Metric"
		(layer "B.Cu")
		(at 140.375 73.75)
		(descr "Capacitor SMD 0402")
		(tags "capacitor SMD 0402")
		(property "Reference" "C41"
			(at 1.125 0.35 0)
			(unlocked yes)
			(layer "B.SilkS")
			(effects
				(font
					(size 0.7 0.7)
					(thickness 0.15)
				)
				(justify right bottom mirror)
			)
		)
		(property "Value" "C_4u7_0402"
			(at -1.022927 -2.155213 0)
			(layer "B.Fab")
			(effects
				(font
					(size 0.7 0.7)
					(thickness 0.15)
				)
				(justify right bottom mirror)
			)
		)
		(property "Author" "Antmicro"
			(at 0 0 0)
			(layer "B.Fab")
			(hide yes)
			(effects
				(font
					(size 1 1)
					(thickness 0.15)
				)
				(justify mirror)
			)
		)
		(property "Dielectric" ""
			(at 0 0 0)
			(layer "B.Fab")
			(hide yes)
			(effects
				(font
					(size 1 1)
					(thickness 0.15)
				)
				(justify mirror)
			)
		)
		(property "License" "Apache-2.0"
			(at 0 0 0)
			(layer "B.Fab")
			(hide yes)
			(effects
				(font
					(size 1 1)
					(thickness 0.15)
				)
				(justify mirror)
			)
		)
		(property "MPN" "GRM155R61A475MEAAD"
			(at 0 0 0)
			(layer "B.Fab")
			(hide yes)
			(effects
				(font
					(size 1 1)
					(thickness 0.15)
				)
				(justify mirror)
			)
		)
		(property "Manufacturer" "Murata"
			(at 0 0 0)
			(layer "B.Fab")
			(hide yes)
			(effects
				(font
					(size 1 1)
					(thickness 0.15)
				)
				(justify mirror)
			)
		)
		(property "Val" "4u7"
			(at 0 0 0)
			(layer "B.Fab")
			(hide yes)
			(effects
				(font
					(size 1 1)
					(thickness 0.15)
				)
				(justify mirror)
			)
		)
		(property "Voltage" ""
			(at 0 0 0)
			(layer "B.Fab")
			(hide yes)
			(effects
				(font
					(size 1 1)
					(thickness 0.15)
				)
				(justify mirror)
			)
		)
		(sheetname "LPDDR5")
		(sheetfile "lpddr5.kicad_sch")
		(attr smd)
		(fp_rect
			(start -0.9659 0.481258)
			(end 0.9649 -0.458742)
			(stroke
				(width 0.05)
				(type solid)
			)
			(fill no)
			(layer "B.CrtYd")
		)
		(fp_line
			(start -0.499 -0.248)
			(end -0.499 0.25)
			(stroke
				(width 0.15)
				(type solid)
			)
			(layer "B.Fab")
		)
		(fp_line
			(start -0.499 0.25)
			(end 0.499 0.25)
			(stroke
				(width 0.15)
				(type solid)
			)
			(layer "B.Fab")
		)
		(fp_line
			(start 0.499 -0.248)
			(end -0.499 -0.248)
			(stroke
				(width 0.15)
				(type solid)
			)
			(layer "B.Fab")
		)
		(fp_line
			(start 0.499 0.25)
			(end 0.499 -0.248)
			(stroke
				(width 0.15)
				(type solid)
			)
			(layer "B.Fab")
		)
		(pad "1" smd roundrect
			(at -0.484 0)
			(size 0.59 0.64)
			(layers "B.Cu" "B.Mask" "B.Paste")
			(roundrect_rratio 0.25)
			(net 14 "GND")
			(pintype "passive")
		)
		(pad "2" smd roundrect
			(at 0.484 0)
			(size 0.59 0.64)
			(layers "B.Cu" "B.Mask" "B.Paste")
			(roundrect_rratio 0.25)
			(net 35 "+1V8")
			(pintype "passive")
		)
	)
)
